# S9S_MB_2U (Grand Teton) — schematic netlist excerpt (pin names and nets, part order shuffled) for the footprints in the layout excerpt that follows; sources: Cadence DE-HDL packaged netlist, KiCad conversion of 03242023_DA0F0TMBIJ0_F0T_Motherboard_J_brd_V01_OCP.brd

R3391  Q_RES  49.9 1% CHIP  pkg 0402LF  page 149 : A = RST_PERST_1_SWB_BUF_R_N ; B = RST_PERST_1_SWB_BUF_N
R3595  Q_RES  33.2 1% CHIP  pkg 0402LF  page 232 : A = SMB_INA230_3V3AUX_SDA ; B = SMB_INA230_4_3V3AUX_SDA_R

(kicad_pcb
	(version 20260206)
	(generator "pcbnew")
	(generator_version "10.0")
	(general
		(thickness 1.6)
		(legacy_teardrops no)
	)
	(paper "A4")
	(title_block
		(title "03242023_DA0F0TMBIJ0_F0T_Motherboard_J_brd_V01_OCP.brd")
		(comment 1 "Grand Teton / footprints 3169-3170 of 6105")
	)
	(layers
		(0 "F.Cu" signal "TOP")
		(4 "In1.Cu" signal "GND")
		(6 "In2.Cu" signal "IN1")
		(8 "In3.Cu" signal "GND1")
		(10 "In4.Cu" signal "IN2")
		(12 "In5.Cu" signal "GND2")
		(14 "In6.Cu" signal "IN3")
		(16 "In7.Cu" signal "GND3")
		(18 "In8.Cu" signal "VCC")
		(20 "In9.Cu" signal "VCC1")
		(22 "In10.Cu" signal "GND4")
		(24 "In11.Cu" signal "IN4")
		(26 "In12.Cu" signal "GND5")
		(28 "In13.Cu" signal "IN5")
		(30 "In14.Cu" signal "GND6")
		(32 "In15.Cu" signal "IN6")
		(34 "In16.Cu" signal "GND7")
		(2 "B.Cu" signal "BOTTOM")
		(9 "F.Adhes" user "F.Adhesive")
		(11 "B.Adhes" user "B.Adhesive")
		(13 "F.Paste" user "Package Geometry/Pastemask Top")
		(15 "B.Paste" user "Package Geometry/Pastemask Bottom")
		(5 "F.SilkS" user "Ref Des/Silkscreen Top")
		(7 "B.SilkS" user "Ref Des/Silkscreen Bottom")
		(1 "F.Mask" user "Board Geometry/Soldermask Top")
		(3 "B.Mask" user "Board Geometry/Soldermask Bottom")
		(17 "Dwgs.User" user "User.Drawings")
		(19 "Cmts.User" user "User.Comments")
		(21 "Eco1.User" user "User.Eco1")
		(23 "Eco2.User" user "User.Eco2")
		(25 "Edge.Cuts" user "Board Geometry/Outline")
		(27 "Margin" user)
		(31 "F.CrtYd" user "Package Geometry/Place Bound Top")
		(29 "B.CrtYd" user "Package Geometry/Place Bound Bottom")
		(35 "F.Fab" user "Ref Des/Assembly Top")
		(33 "B.Fab" user "Ref Des/Assembly Bottom")
	)
	(footprint ""
		(layer "F.Cu")
		(at 150.67788 -45.938948 90)
		(property "Reference" "R3595"
			(at 0 0 90)
			(layer "F.SilkS")
			(hide yes)
			(effects
				(font
					(size 1.27 1.27)
				)
			)
		)
		(property "Value" ""
			(at 0 0 90)
			(layer "F.Fab")
			(effects
				(font
					(size 1.27 1.27)
				)
			)
		)
		(duplicate_pad_numbers_are_jumpers no)
		(fp_line
			(start 0.7874 -0.4064)
			(end 0.7874 0.4064)
			(stroke
				(width 0.1524)
				(type default)
			)
			(layer "F.SilkS")
		)
		(fp_line
			(start -0.7874 -0.4064)
			(end 0.7874 -0.4064)
			(stroke
				(width 0.1524)
				(type default)
			)
			(layer "F.SilkS")
		)
		(fp_line
			(start 0.7874 0.4064)
			(end -0.7874 0.4064)
			(stroke
				(width 0.1524)
				(type default)
			)
			(layer "F.SilkS")
		)
		(fp_line
			(start -0.7874 0.4064)
			(end -0.7874 -0.4064)
			(stroke
				(width 0.1524)
				(type default)
			)
			(layer "F.SilkS")
		)
		(fp_line
			(start -0.12065 -0.305054)
			(end -0.12065 -0.2794)
			(stroke
				(width 0.1)
				(type default)
			)
			(layer "F.Fab")
		)
		(fp_line
			(start -0.67945 -0.305054)
			(end -0.12065 -0.305054)
			(stroke
				(width 0.1)
				(type default)
			)
			(layer "F.Fab")
		)
		(fp_line
			(start 0.67945 -0.3048)
			(end 0.67945 0.3048)
			(stroke
				(width 0.1)
				(type default)
			)
			(layer "F.Fab")
		)
		(fp_line
			(start 0.12065 -0.3048)
			(end 0.67945 -0.3048)
			(stroke
				(width 0.1)
				(type default)
			)
			(layer "F.Fab")
		)
		(fp_line
			(start 0.12065 -0.2794)
			(end 0.12065 -0.3048)
			(stroke
				(width 0.1)
				(type default)
			)
			(layer "F.Fab")
		)
		(fp_line
			(start -0.12065 -0.2794)
			(end 0.12065 -0.2794)
			(stroke
				(width 0.1)
				(type default)
			)
			(layer "F.Fab")
		)
		(fp_line
			(start 0.120396 0.2794)
			(end -0.12065 0.2794)
			(stroke
				(width 0.1)
				(type default)
			)
			(layer "F.Fab")
		)
		(fp_line
			(start -0.12065 0.2794)
			(end -0.12065 0.3048)
			(stroke
				(width 0.1)
				(type default)
			)
			(layer "F.Fab")
		)
		(fp_line
			(start 0.67945 0.3048)
			(end 0.120396 0.3048)
			(stroke
				(width 0.1)
				(type default)
			)
			(layer "F.Fab")
		)
		(fp_line
			(start 0.120396 0.3048)
			(end 0.120396 0.2794)
			(stroke
				(width 0.1)
				(type default)
			)
			(layer "F.Fab")
		)
		(fp_line
			(start -0.12065 0.3048)
			(end -0.67945 0.3048)
			(stroke
				(width 0.1)
				(type default)
			)
			(layer "F.Fab")
		)
		(fp_line
			(start -0.67945 0.3048)
			(end -0.67945 -0.305054)
			(stroke
				(width 0.1)
				(type default)
			)
			(layer "F.Fab")
		)
		(pad "1" smd circle
			(at -0.40005 0 90)
			(size 0 0)
			(layers "F.Cu" "F.Mask" "F.Paste")
			(net "SMB_INA230_3V3AUX_SDA")
		)
		(pad "2" smd circle
			(at 0.40005 0 90)
			(size 0 0)
			(layers "F.Cu" "F.Mask" "F.Paste")
			(net "SMB_INA230_4_3V3AUX_SDA_R")
		)
	)
	(footprint ""
		(layer "F.Cu")
		(at 31.29788 -425.287948)
		(property "Reference" "R3391"
			(at 0 0 0)
			(layer "F.SilkS")
			(hide yes)
			(effects
				(font
					(size 1.27 1.27)
				)
			)
		)
		(property "Value" ""
			(at 0 0 0)
			(layer "F.Fab")
			(effects
				(font
					(size 1.27 1.27)
				)
			)
		)
		(duplicate_pad_numbers_are_jumpers no)
		(fp_line
			(start -0.7874 -0.4064)
			(end 0.7874 -0.4064)
			(stroke
				(width 0.1524)
				(type default)
			)
			(layer "F.SilkS")
		)
		(fp_line
			(start -0.7874 0.4064)
			(end -0.7874 -0.4064)
			(stroke
				(width 0.1524)
				(type default)
			)
			(layer "F.SilkS")
		)
		(fp_line
			(start 0.7874 -0.4064)
			(end 0.7874 0.4064)
			(stroke
				(width 0.1524)
				(type default)
			)
			(layer "F.SilkS")
		)
		(fp_line
			(start 0.7874 0.4064)
			(end -0.7874 0.4064)
			(stroke
				(width 0.1524)
				(type default)
			)
			(layer "F.SilkS")
		)
		(fp_line
			(start -0.67945 -0.305054)
			(end -0.12065 -0.305054)
			(stroke
				(width 0.1)
				(type default)
			)
			(layer "F.Fab")
		)
		(fp_line
			(start -0.67945 0.3048)
			(end -0.67945 -0.305054)
			(stroke
				(width 0.1)
				(type default)
			)
			(layer "F.Fab")
		)
		(fp_line
			(start -0.12065 -0.305054)
			(end -0.12065 -0.2794)
			(stroke
				(width 0.1)
				(type default)
			)
			(layer "F.Fab")
		)
		(fp_line
			(start -0.12065 -0.2794)
			(end 0.12065 -0.2794)
			(stroke
				(width 0.1)
				(type default)
			)
			(layer "F.Fab")
		)
		(fp_line
			(start -0.12065 0.2794)
			(end -0.12065 0.3048)
			(stroke
				(width 0.1)
				(type default)
			)
			(layer "F.Fab")
		)
		(fp_line
			(start -0.12065 0.3048)
			(end -0.67945 0.3048)
			(stroke
				(width 0.1)
				(type default)
			)
			(layer "F.Fab")
		)
		(fp_line
			(start 0.120396 0.2794)
			(end -0.12065 0.2794)
			(stroke
				(width 0.1)
				(type default)
			)
			(layer "F.Fab")
		)
		(fp_line
			(start 0.120396 0.3048)
			(end 0.120396 0.2794)
			(stroke
				(width 0.1)
				(type default)
			)
			(layer "F.Fab")
		)
		(fp_line
			(start 0.12065 -0.3048)
			(end 0.67945 -0.3048)
			(stroke
				(width 0.1)
				(type default)
			)
			(layer "F.Fab")
		)
		(fp_line
			(start 0.12065 -0.2794)
			(end 0.12065 -0.3048)
			(stroke
				(width 0.1)
				(type default)
			)
			(layer "F.Fab")
		)
		(fp_line
			(start 0.67945 -0.3048)
			(end 0.67945 0.3048)
			(stroke
				(width 0.1)
				(type default)
			)
			(layer "F.Fab")
		)
		(fp_line
			(start 0.67945 0.3048)
			(end 0.120396 0.3048)
			(stroke
				(width 0.1)
				(type default)
			)
			(layer "F.Fab")
		)
		(pad "1" smd circle
			(at -0.40005 0)
			(size 0 0)
			(layers "F.Cu" "F.Mask" "F.Paste")
			(net "RST_PERST_1_SWB_BUF_R_N")
		)
		(pad "2" smd circle
			(at 0.40005 0)
			(size 0 0)
			(layers "F.Cu" "F.Mask" "F.Paste")
			(net "RST_PERST_1_SWB_BUF_N")
		)
	)
)
